(kicad_pcb
	(version 20260206)
	(generator "pcbnew")
	(generator_version "10.0")
	(general
		(thickness 1.6)
		(legacy_teardrops no)
	)
	(paper "A4")
	(title_block
		(title "Bryce Canyon_F.DPB_16315-1-OCP.brd")
		(comment 1 "Bryce Canyon / footprints 795-801 of 2223")
	)
	(layers
		(0 "F.Cu" signal "TOP")
		(4 "In1.Cu" signal "L2GND")
		(6 "In2.Cu" signal "L3")
		(8 "In3.Cu" signal "L4GND")
		(10 "In4.Cu" signal "L5")
		(12 "In5.Cu" signal "L6VCC")
		(14 "In6.Cu" signal "L7VCC")
		(16 "In7.Cu" signal "L8")
		(18 "In8.Cu" signal "L9GND")
		(20 "In9.Cu" signal "L10")
		(22 "In10.Cu" signal "L11GND")
		(2 "B.Cu" signal "BOTTOM")
		(9 "F.Adhes" user "F.Adhesive")
		(11 "B.Adhes" user "B.Adhesive")
		(13 "F.Paste" user "Package Geometry/Pastemask Top")
		(15 "B.Paste" user "Package Geometry/Pastemask Bottom")
		(5 "F.SilkS" user "Ref Des/Silkscreen Top")
		(7 "B.SilkS" user "Ref Des/Silkscreen Bottom")
		(1 "F.Mask" user "Board Geometry/Soldermask Top")
		(3 "B.Mask" user "Board Geometry/Soldermask Bottom")
		(17 "Dwgs.User" user "User.Drawings")
		(19 "Cmts.User" user "User.Comments")
		(21 "Eco1.User" user "User.Eco1")
		(23 "Eco2.User" user "User.Eco2")
		(25 "Edge.Cuts" user "Board Geometry/Outline")
		(27 "Margin" user)
		(31 "F.CrtYd" user "Package Geometry/Place Bound Top")
		(29 "B.CrtYd" user "Package Geometry/Place Bound Bottom")
		(35 "F.Fab" user "Ref Des/Assembly Top")
		(33 "B.Fab" user "Ref Des/Assembly Bottom")
	)
	(footprint ""
		(layer "F.Cu")
		(at 47.853346 -169.567606 -90)
		(property "Reference" "R442"
			(at 0 0 270)
			(layer "F.SilkS")
			(hide yes)
			(effects
				(font
					(size 1.27 1.27)
				)
			)
		)
		(property "Value" "300KR2F-GP"
			(at 0.064008 -3.993896 270)
			(unlocked yes)
			(layer "F.Fab")
			(hide yes)
			(effects
				(font
					(size 1.016 1.016)
					(thickness 0.1524)
				)
			)
		)
		(property "Device Type" "R402H16"
			(at 0.064008 -5.517896 270)
			(unlocked yes)
			(layer "F.Fab")
			(hide yes)
			(effects
				(font
					(size 1.016 1.016)
					(thickness 0.1524)
				)
			)
		)
		(duplicate_pad_numbers_are_jumpers no)
		(fp_line
			(start -0.508 -0.9398)
			(end -0.508 0.9398)
			(stroke
				(width 0.1524)
				(type default)
			)
			(layer "F.SilkS")
		)
		(fp_line
			(start 0.508 -0.9398)
			(end -0.508 -0.9398)
			(stroke
				(width 0.1524)
				(type default)
			)
			(layer "F.SilkS")
		)
		(fp_rect
			(start -0.508 0.9398)
			(end 0.508 -0.9398)
			(stroke
				(width 0)
				(type default)
			)
			(fill no)
			(layer "F.CrtYd")
		)
		(fp_rect
			(start -0.508 0.9398)
			(end 0.508 -0.9398)
			(stroke
				(width 0)
				(type default)
			)
			(fill no)
			(layer "F.Fab")
		)
		(pad "1" smd custom
			(at 0 -0.4445 270)
			(size 0.1397 0.1397)
			(layers "F.Cu" "F.Mask" "F.Paste")
			(net "SW_HDD_N13")
			(options
				(clearance outline)
				(anchor circle)
			)
			(primitives
				(gr_poly
					(pts
						(arc
							(start -0.1778 -0.2794)
							(mid -0.249642 -0.249642)
							(end -0.2794 -0.1778)
						)
						(arc
							(start -0.2794 0.1778)
							(mid -0.249642 0.249642)
							(end -0.1778 0.2794)
						)
						(arc
							(start 0.1778 0.2794)
							(mid 0.249642 0.249642)
							(end 0.2794 0.1778)
						)
						(arc
							(start 0.2794 -0.1778)
							(mid 0.249642 -0.249642)
							(end 0.1778 -0.2794)
						)
					)
					(width 0)
					(fill yes)
				)
			)
		)
		(pad "2" smd custom
			(at 0 0.4445 270)
			(size 0.1397 0.1397)
			(layers "F.Cu" "F.Mask" "F.Paste")
			(net "P12V_A")
			(options
				(clearance outline)
				(anchor circle)
			)
			(primitives
				(gr_poly
					(pts
						(arc
							(start -0.1778 -0.2794)
							(mid -0.249642 -0.249642)
							(end -0.2794 -0.1778)
						)
						(arc
							(start -0.2794 0.1778)
							(mid -0.249642 0.249642)
							(end -0.1778 0.2794)
						)
						(arc
							(start 0.1778 0.2794)
							(mid 0.249642 0.249642)
							(end 0.2794 0.1778)
						)
						(arc
							(start 0.2794 -0.1778)
							(mid 0.249642 -0.249642)
							(end 0.1778 -0.2794)
						)
					)
					(width 0)
					(fill yes)
				)
			)
		)
	)
	(footprint ""
		(layer "F.Cu")
		(at 155.42514 -140.556996)
		(property "Reference" "R1066"
			(at 0 0 0)
			(layer "F.SilkS")
			(hide yes)
			(effects
				(font
					(size 1.27 1.27)
				)
			)
		)
		(property "Value" "5K1R2F-3-GP"
			(at 0.064008 -3.993896 0)
			(unlocked yes)
			(layer "F.Fab")
			(hide yes)
			(effects
				(font
					(size 1.016 1.016)
					(thickness 0.1524)
				)
			)
		)
		(property "Device Type" "R402H16"
			(at 0.064008 -5.517896 0)
			(unlocked yes)
			(layer "F.Fab")
			(hide yes)
			(effects
				(font
					(size 1.016 1.016)
					(thickness 0.1524)
				)
			)
		)
		(duplicate_pad_numbers_are_jumpers no)
		(fp_line
			(start -0.508 -0.9398)
			(end -0.508 0.9398)
			(stroke
				(width 0.1524)
				(type default)
			)
			(layer "F.SilkS")
		)
		(fp_line
			(start 0.508 -0.9398)
			(end -0.508 -0.9398)
			(stroke
				(width 0.1524)
				(type default)
			)
			(layer "F.SilkS")
		)
		(fp_rect
			(start -0.508 0.9398)
			(end 0.508 -0.9398)
			(stroke
				(width 0)
				(type default)
			)
			(fill no)
			(layer "F.CrtYd")
		)
		(fp_rect
			(start -0.508 0.9398)
			(end 0.508 -0.9398)
			(stroke
				(width 0)
				(type default)
			)
			(fill no)
			(layer "F.Fab")
		)
		(pad "1" smd custom
			(at 0 -0.4445)
			(size 0.1397 0.1397)
			(layers "F.Cu" "F.Mask" "F.Paste")
			(net "MB0_CM_UV_R")
			(options
				(clearance outline)
				(anchor circle)
			)
			(primitives
				(gr_poly
					(pts
						(arc
							(start -0.1778 -0.2794)
							(mid -0.249642 -0.249642)
							(end -0.2794 -0.1778)
						)
						(arc
							(start -0.2794 0.1778)
							(mid -0.249642 0.249642)
							(end -0.1778 0.2794)
						)
						(arc
							(start 0.1778 0.2794)
							(mid 0.249642 0.249642)
							(end 0.2794 0.1778)
						)
						(arc
							(start 0.2794 -0.1778)
							(mid 0.249642 -0.249642)
							(end 0.1778 -0.2794)
						)
					)
					(width 0)
					(fill yes)
				)
			)
		)
		(pad "2" smd custom
			(at 0 0.4445)
			(size 0.1397 0.1397)
			(layers "F.Cu" "F.Mask" "F.Paste")
			(net "AGND_CURRENT_MONOA")
			(options
				(clearance outline)
				(anchor circle)
			)
			(primitives
				(gr_poly
					(pts
						(arc
							(start -0.1778 -0.2794)
							(mid -0.249642 -0.249642)
							(end -0.2794 -0.1778)
						)
						(arc
							(start -0.2794 0.1778)
							(mid -0.249642 0.249642)
							(end -0.1778 0.2794)
						)
						(arc
							(start 0.1778 0.2794)
							(mid 0.249642 0.249642)
							(end 0.2794 0.1778)
						)
						(arc
							(start 0.2794 -0.1778)
							(mid 0.249642 -0.249642)
							(end 0.1778 -0.2794)
						)
					)
					(width 0)
					(fill yes)
				)
			)
		)
	)
	(footprint ""
		(layer "F.Cu")
		(at 55.282846 -177.270918)
		(property "Reference" "R428"
			(at 0 0 0)
			(layer "F.SilkS")
			(hide yes)
			(effects
				(font
					(size 1.27 1.27)
				)
			)
		)
		(property "Value" "2R6F-GP"
			(at -0.0508 -4.8514 0)
			(unlocked yes)
			(layer "F.Fab")
			(hide yes)
			(effects
				(font
					(size 1.016 1.016)
					(thickness 0.1524)
				)
			)
		)
		(property "Device Type" "R1206H26"
			(at 0 -6.3754 0)
			(unlocked yes)
			(layer "F.Fab")
			(hide yes)
			(effects
				(font
					(size 1.016 1.016)
					(thickness 0.1524)
				)
			)
		)
		(duplicate_pad_numbers_are_jumpers no)
		(fp_line
			(start -1.016 -2.2352)
			(end 1.016 -2.2352)
			(stroke
				(width 0.1524)
				(type default)
			)
			(layer "F.SilkS")
		)
		(fp_line
			(start -1.016 2.2352)
			(end -1.016 -2.2352)
			(stroke
				(width 0.1524)
				(type default)
			)
			(layer "F.SilkS")
		)
		(fp_line
			(start 1.016 -2.2352)
			(end 1.016 2.2352)
			(stroke
				(width 0.1524)
				(type default)
			)
			(layer "F.SilkS")
		)
		(fp_line
			(start 1.016 2.2352)
			(end -1.016 2.2352)
			(stroke
				(width 0.1524)
				(type default)
			)
			(layer "F.SilkS")
		)
		(fp_rect
			(start -1.0922 2.3114)
			(end 1.0922 -2.3114)
			(stroke
				(width 0)
				(type default)
			)
			(fill no)
			(layer "F.CrtYd")
		)
		(fp_poly
			(pts
				(xy -1.0922 -2.3114) (xy 1.0922 -2.3114) (xy 1.0922 2.3114) (xy -1.0922 2.3114)
			)
			(stroke
				(width 0)
				(type default)
			)
			(fill no)
			(layer "F.Fab")
		)
		(pad "1" smd rect
			(at 0 -1.397)
			(size 1.651 1.27)
			(layers "F.Cu" "F.Mask" "F.Paste")
			(net "P5V_HDD13")
		)
		(pad "2" smd rect
			(at 0 1.397)
			(size 1.651 1.27)
			(layers "F.Cu" "F.Mask" "F.Paste")
			(net "5V_PRE_13")
		)
	)
	(footprint ""
		(layer "F.Cu")
		(at 376.9614 -141.2494 90)
		(property "Reference" "R1077"
			(at 0 0 90)
			(layer "F.SilkS")
			(hide yes)
			(effects
				(font
					(size 1.27 1.27)
				)
			)
		)
		(property "Value" "0R2J-2-GP"
			(at 0.064008 -3.993896 90)
			(unlocked yes)
			(layer "F.Fab")
			(hide yes)
			(effects
				(font
					(size 1.016 1.016)
					(thickness 0.1524)
				)
			)
		)
		(property "Device Type" "R402H16"
			(at 0.064008 -5.517896 90)
			(unlocked yes)
			(layer "F.Fab")
			(hide yes)
			(effects
				(font
					(size 1.016 1.016)
					(thickness 0.1524)
				)
			)
		)
		(duplicate_pad_numbers_are_jumpers no)
		(fp_line
			(start 0.508 -0.9398)
			(end -0.508 -0.9398)
			(stroke
				(width 0.1524)
				(type default)
			)
			(layer "F.SilkS")
		)
		(fp_line
			(start -0.508 -0.9398)
			(end -0.508 0.9398)
			(stroke
				(width 0.1524)
				(type default)
			)
			(layer "F.SilkS")
		)
		(fp_rect
			(start -0.508 0.9398)
			(end 0.508 -0.9398)
			(stroke
				(width 0)
				(type default)
			)
			(fill no)
			(layer "F.CrtYd")
		)
		(fp_rect
			(start -0.508 0.9398)
			(end 0.508 -0.9398)
			(stroke
				(width 0)
				(type default)
			)
			(fill no)
			(layer "F.Fab")
		)
		(pad "1" smd custom
			(at 0 -0.4445 90)
			(size 0.1397 0.1397)
			(layers "F.Cu" "F.Mask" "F.Paste")
			(net "MB1_SDA_R")
			(options
				(clearance outline)
				(anchor circle)
			)
			(primitives
				(gr_poly
					(pts
						(arc
							(start -0.1778 -0.2794)
							(mid -0.249642 -0.249642)
							(end -0.2794 -0.1778)
						)
						(arc
							(start -0.2794 0.1778)
							(mid -0.249642 0.249642)
							(end -0.1778 0.2794)
						)
						(arc
							(start 0.1778 0.2794)
							(mid 0.249642 0.249642)
							(end 0.2794 0.1778)
						)
						(arc
							(start 0.2794 -0.1778)
							(mid 0.249642 -0.249642)
							(end 0.1778 -0.2794)
						)
					)
					(width 0)
					(fill yes)
				)
			)
		)
		(pad "2" smd custom
			(at 0 0.4445 90)
			(size 0.1397 0.1397)
			(layers "F.Cu" "F.Mask" "F.Paste")
			(net "I2C_BMC_B_MISC_SDA")
			(options
				(clearance outline)
				(anchor circle)
			)
			(primitives
				(gr_poly
					(pts
						(arc
							(start -0.1778 -0.2794)
							(mid -0.249642 -0.249642)
							(end -0.2794 -0.1778)
						)
						(arc
							(start -0.2794 0.1778)
							(mid -0.249642 0.249642)
							(end -0.1778 0.2794)
						)
						(arc
							(start 0.1778 0.2794)
							(mid 0.249642 0.249642)
							(end 0.2794 0.1778)
						)
						(arc
							(start 0.2794 -0.1778)
							(mid 0.249642 -0.249642)
							(end 0.1778 -0.2794)
						)
					)
					(width 0)
					(fill yes)
				)
			)
		)
	)
	(footprint ""
		(layer "F.Cu")
		(at 347.315028 -242.25377)
		(property "Reference" "R246"
			(at 0 0 0)
			(layer "F.SilkS")
			(hide yes)
			(effects
				(font
					(size 1.27 1.27)
				)
			)
		)
		(property "Value" "91R3F-1-GP"
			(at -0.0254 -2.5146 0)
			(unlocked yes)
			(layer "F.Fab")
			(hide yes)
			(effects
				(font
					(size 1.016 1.016)
					(thickness 0.1524)
				)
			)
		)
		(property "Device Type" "R603H22"
			(at -0.0254 -4.0386 0)
			(unlocked yes)
			(layer "F.Fab")
			(hide yes)
			(effects
				(font
					(size 1.016 1.016)
					(thickness 0.1524)
				)
			)
		)
		(duplicate_pad_numbers_are_jumpers no)
		(fp_line
			(start -0.4826 0)
			(end -0.2032 0)
			(stroke
				(width 0.2032)
				(type default)
			)
			(layer "F.SilkS")
		)
		(fp_line
			(start 0.2032 0)
			(end 0.4826 0)
			(stroke
				(width 0.2032)
				(type default)
			)
			(layer "F.SilkS")
		)
		(fp_rect
			(start -0.5842 1.3335)
			(end 0.5842 -1.3335)
			(stroke
				(width 0)
				(type default)
			)
			(fill no)
			(layer "F.CrtYd")
		)
		(fp_rect
			(start -0.5842 1.3335)
			(end 0.5842 -1.3335)
			(stroke
				(width 0)
				(type default)
			)
			(fill no)
			(layer "F.Fab")
		)
		(pad "1" smd custom
			(at 0 -0.762)
			(size 0.2159 0.2159)
			(layers "F.Cu" "F.Mask" "F.Paste")
			(net "P5V_A_3")
			(options
				(clearance outline)
				(anchor circle)
			)
			(primitives
				(gr_poly
					(pts
						(arc
							(start -0.3302 -0.4318)
							(mid -0.402042 -0.402042)
							(end -0.4318 -0.3302)
						)
						(arc
							(start -0.4318 0.3302)
							(mid -0.402042 0.402042)
							(end -0.3302 0.4318)
						)
						(arc
							(start 0.3302 0.4318)
							(mid 0.402042 0.402042)
							(end 0.4318 0.3302)
						)
						(arc
							(start 0.4318 -0.3302)
							(mid 0.402042 -0.402042)
							(end 0.3302 -0.4318)
						)
					)
					(width 0)
					(fill yes)
				)
			)
		)
		(pad "2" smd custom
			(at 0 0.762)
			(size 0.2159 0.2159)
			(layers "F.Cu" "F.Mask" "F.Paste")
			(net "DRV_ACT_7")
			(options
				(clearance outline)
				(anchor circle)
			)
			(primitives
				(gr_poly
					(pts
						(arc
							(start -0.3302 -0.4318)
							(mid -0.402042 -0.402042)
							(end -0.4318 -0.3302)
						)
						(arc
							(start -0.4318 0.3302)
							(mid -0.402042 0.402042)
							(end -0.3302 0.4318)
						)
						(arc
							(start 0.3302 0.4318)
							(mid 0.402042 0.402042)
							(end 0.4318 0.3302)
						)
						(arc
							(start 0.4318 -0.3302)
							(mid 0.402042 -0.402042)
							(end 0.3302 -0.4318)
						)
					)
					(width 0)
					(fill yes)
				)
			)
		)
	)
	(footprint ""
		(layer "F.Cu")
		(at 475.812866 -281.371802 180)
		(property "Reference" "Q66"
			(at 0 0 180)
			(layer "F.SilkS")
			(hide yes)
			(effects
				(font
					(size 1.27 1.27)
				)
			)
		)
		(property "Value" "AO4406AL-GP"
			(at -3.707384 -1.5367 180)
			(unlocked yes)
			(layer "F.Fab")
			(hide yes)
			(effects
				(font
					(size 1.016 1.016)
					(thickness 0.1524)
				)
			)
		)
		(property "Device Type" "SOIC8H69"
			(at -3.707384 -3.0607 180)
			(unlocked yes)
			(layer "F.Fab")
			(hide yes)
			(effects
				(font
					(size 1.016 1.016)
					(thickness 0.1524)
				)
			)
		)
		(duplicate_pad_numbers_are_jumpers no)
		(fp_line
			(start 2.1336 1.4224)
			(end 2.1336 -1.4224)
			(stroke
				(width 0.1524)
				(type default)
			)
			(layer "F.SilkS")
		)
		(fp_line
			(start 2.1336 -1.4224)
			(end -2.7432 -1.4224)
			(stroke
				(width 0.1524)
				(type default)
			)
			(layer "F.SilkS")
		)
		(fp_line
			(start -2.1844 -0.0508)
			(end -2.7178 0.508)
			(stroke
				(width 0.1524)
				(type default)
			)
			(layer "F.SilkS")
		)
		(fp_line
			(start -2.6289 3.4417)
			(end -2.6289 1.4732)
			(stroke
				(width 0.381)
				(type default)
			)
			(layer "F.SilkS")
		)
		(fp_line
			(start -2.7178 -0.508)
			(end -2.1844 -0.0508)
			(stroke
				(width 0.1524)
				(type default)
			)
			(layer "F.SilkS")
		)
		(fp_line
			(start -2.7432 1.4224)
			(end 2.1336 1.4224)
			(stroke
				(width 0.1524)
				(type default)
			)
			(layer "F.SilkS")
		)
		(fp_line
			(start -2.7432 1.4224)
			(end -2.6416 1.4224)
			(stroke
				(width 0.1524)
				(type default)
			)
			(layer "F.SilkS")
		)
		(fp_line
			(start -2.7432 -1.4224)
			(end -2.7432 1.4224)
			(stroke
				(width 0.1524)
				(type default)
			)
			(layer "F.SilkS")
		)
		(fp_poly
			(pts
				(xy -2.2098 -1.4224) (xy -2.2098 1.4224) (xy 2.2098 1.4224) (xy 2.2098 -1.4224)
			)
			(stroke
				(width 0)
				(type default)
			)
			(fill yes)
			(layer "F.SilkS")
		)
		(fp_rect
			(start -2.450084 2.999994)
			(end 2.450084 -2.999994)
			(stroke
				(width 0)
				(type default)
			)
			(fill no)
			(layer "F.CrtYd")
		)
		(fp_poly
			(pts
				(xy -2.8194 3.6322) (xy -2.8194 -3.6322) (xy 2.8194 -3.6322) (xy 2.8194 1.18364) (xy 2.450084 1.18364)
				(xy 2.450084 -2.999994) (xy -2.450084 -2.999994) (xy -2.450084 2.999994) (xy 2.450084 2.999994)
				(xy 2.450084 1.18618) (xy 2.8194 1.18618) (xy 2.8194 3.6322)
			)
			(stroke
				(width 0)
				(type default)
			)
			(fill no)
			(layer "F.CrtYd")
		)
		(fp_rect
			(start -2.8194 3.6322)
			(end 2.8194 -3.6322)
			(stroke
				(width 0)
				(type default)
			)
			(fill no)
			(layer "F.Fab")
		)
		(pad "1" smd rect
			(at -1.905 2.54 180)
			(size 0.635 1.651)
			(layers "F.Cu" "F.Mask" "F.Paste")
			(net "P5V_HDD11")
		)
		(pad "2" smd rect
			(at -0.635 2.54 180)
			(size 0.635 1.651)
			(layers "F.Cu" "F.Mask" "F.Paste")
			(net "P5V_HDD11")
		)
		(pad "3" smd rect
			(at 0.635 2.54 180)
			(size 0.635 1.651)
			(layers "F.Cu" "F.Mask" "F.Paste")
			(net "P5V_HDD11")
		)
		(pad "4" smd rect
			(at 1.905 2.54 180)
			(size 0.635 1.651)
			(layers "F.Cu" "F.Mask" "F.Paste")
			(net "SW_HDD_P11")
		)
		(pad "5" smd rect
			(at 1.905 -2.54 180)
			(size 0.635 1.651)
			(layers "F.Cu" "F.Mask" "F.Paste")
			(net "P5V_A_3")
		)
		(pad "6" smd rect
			(at 0.635 -2.54 180)
			(size 0.635 1.651)
			(layers "F.Cu" "F.Mask" "F.Paste")
			(net "P5V_A_3")
		)
		(pad "7" smd rect
			(at -0.635 -2.54 180)
			(size 0.635 1.651)
			(layers "F.Cu" "F.Mask" "F.Paste")
			(net "P5V_A_3")
		)
		(pad "8" smd rect
			(at -1.905 -2.54 180)
			(size 0.635 1.651)
			(layers "F.Cu" "F.Mask" "F.Paste")
			(net "P5V_A_3")
		)
	)
	(footprint ""
		(layer "F.Cu")
		(at 361.180126 -134.532878 180)
		(property "Reference" "R1100"
			(at 0 0 180)
			(layer "F.SilkS")
			(hide yes)
			(effects
				(font
					(size 1.27 1.27)
				)
			)
		)
		(property "Value" "5K1R2F-3-GP"
			(at 0.064008 -3.993896 180)
			(unlocked yes)
			(layer "F.Fab")
			(hide yes)
			(effects
				(font
					(size 1.016 1.016)
					(thickness 0.1524)
				)
			)
		)
		(property "Device Type" "R402H16"
			(at 0.064008 -5.517896 180)
			(unlocked yes)
			(layer "F.Fab")
			(hide yes)
			(effects
				(font
					(size 1.016 1.016)
					(thickness 0.1524)
				)
			)
		)
		(duplicate_pad_numbers_are_jumpers no)
		(fp_line
			(start 0.508 -0.9398)
			(end -0.508 -0.9398)
			(stroke
				(width 0.1524)
				(type default)
			)
			(layer "F.SilkS")
		)
		(fp_line
			(start -0.508 -0.9398)
			(end -0.508 0.9398)
			(stroke
				(width 0.1524)
				(type default)
			)
			(layer "F.SilkS")
		)
		(fp_rect
			(start -0.508 0.9398)
			(end 0.508 -0.9398)
			(stroke
				(width 0)
				(type default)
			)
			(fill no)
			(layer "F.CrtYd")
		)
		(fp_rect
			(start -0.508 0.9398)
			(end 0.508 -0.9398)
			(stroke
				(width 0)
				(type default)
			)
			(fill no)
			(layer "F.Fab")
		)
		(pad "1" smd custom
			(at 0 -0.4445 180)
			(size 0.1397 0.1397)
			(layers "F.Cu" "F.Mask" "F.Paste")
			(net "MB1_CM_UV_R")
			(options
				(clearance outline)
				(anchor circle)
			)
			(primitives
				(gr_poly
					(pts
						(arc
							(start -0.1778 -0.2794)
							(mid -0.249642 -0.249642)
							(end -0.2794 -0.1778)
						)
						(arc
							(start -0.2794 0.1778)
							(mid -0.249642 0.249642)
							(end -0.1778 0.2794)
						)
						(arc
							(start 0.1778 0.2794)
							(mid 0.249642 0.249642)
							(end 0.2794 0.1778)
						)
						(arc
							(start 0.2794 -0.1778)
							(mid 0.249642 -0.249642)
							(end 0.1778 -0.2794)
						)
					)
					(width 0)
					(fill yes)
				)
			)
		)
		(pad "2" smd custom
			(at 0 0.4445 180)
			(size 0.1397 0.1397)
			(layers "F.Cu" "F.Mask" "F.Paste")
			(net "AGND_CURRENT_MONOB")
			(options
				(clearance outline)
				(anchor circle)
			)
			(primitives
				(gr_poly
					(pts
						(arc
							(start -0.1778 -0.2794)
							(mid -0.249642 -0.249642)
							(end -0.2794 -0.1778)
						)
						(arc
							(start -0.2794 0.1778)
							(mid -0.249642 0.249642)
							(end -0.1778 0.2794)
						)
						(arc
							(start 0.1778 0.2794)
							(mid 0.249642 0.249642)
							(end 0.2794 0.1778)
						)
						(arc
							(start 0.2794 -0.1778)
							(mid 0.249642 -0.249642)
							(end 0.1778 -0.2794)
						)
					)
					(width 0)
					(fill yes)
				)
			)
		)
	)
)
